(kicad_pcb
	(version 20260206)
	(generator "pcbnew")
	(generator_version "10.0")
	(general
		(thickness 1.6)
		(legacy_teardrops no)
	)
	(paper "A4")
	(title_block
		(title "Bryce Canyon_F.DPB_16315-1-OCP.brd")
		(comment 1 "Bryce Canyon / footprint 2079 of 2223 (IO1), pads 96-109 of 202")
	)
	(layers
		(0 "F.Cu" signal "TOP")
		(4 "In1.Cu" signal "L2GND")
		(6 "In2.Cu" signal "L3")
		(8 "In3.Cu" signal "L4GND")
		(10 "In4.Cu" signal "L5")
		(12 "In5.Cu" signal "L6VCC")
		(14 "In6.Cu" signal "L7VCC")
		(16 "In7.Cu" signal "L8")
		(18 "In8.Cu" signal "L9GND")
		(20 "In9.Cu" signal "L10")
		(22 "In10.Cu" signal "L11GND")
		(2 "B.Cu" signal "BOTTOM")
		(9 "F.Adhes" user "F.Adhesive")
		(11 "B.Adhes" user "B.Adhesive")
		(13 "F.Paste" user "Package Geometry/Pastemask Top")
		(15 "B.Paste" user "Package Geometry/Pastemask Bottom")
		(5 "F.SilkS" user "Ref Des/Silkscreen Top")
		(7 "B.SilkS" user "Ref Des/Silkscreen Bottom")
		(1 "F.Mask" user "Board Geometry/Soldermask Top")
		(3 "B.Mask" user "Board Geometry/Soldermask Bottom")
		(17 "Dwgs.User" user "User.Drawings")
		(19 "Cmts.User" user "User.Comments")
		(21 "Eco1.User" user "User.Eco1")
		(23 "Eco2.User" user "User.Eco2")
		(25 "Edge.Cuts" user "Board Geometry/Outline")
		(27 "Margin" user)
		(31 "F.CrtYd" user "Package Geometry/Place Bound Top")
		(29 "B.CrtYd" user "Package Geometry/Place Bound Bottom")
		(35 "F.Fab" user "Ref Des/Assembly Top")
		(33 "B.Fab" user "Ref Des/Assembly Bottom")
	)
	(footprint ""
		(layer "B.Cu")
		(at 143.34998 -30.550104 180)
		(property "Reference" "IO1"
			(at 0 0 0)
			(layer "B.SilkS")
			(hide yes)
			(effects
				(font
					(size 1.27 1.27)
				)
				(justify mirror)
			)
		)
		(property "Value" "DM-AMP-CONN200-13R-6-GP-01"
			(at 47.5488 -16.5862 180)
			(unlocked yes)
			(layer "B.Fab")
			(hide yes)
			(effects
				(font
					(size 1.016 1.016)
					(thickness 0.1524)
				)
				(justify mirror)
			)
		)
		(property "Device Type" "DMFIT-200P-384346H577-01"
			(at 47.5488 -18.1102 180)
			(unlocked yes)
			(layer "B.Fab")
			(hide yes)
			(effects
				(font
					(size 1.016 1.016)
					(thickness 0.1524)
				)
				(justify mirror)
			)
		)
		(duplicate_pad_numbers_are_jumpers no)
		(pad "F14" thru_hole circle
			(at 30.599888 -9.59993)
			(size 0.664718 0.664718)
			(drill 0.359918)
			(layers "*.Cu" "*.Mask")
			(remove_unused_layers no)
			(net "PCIE_IOM_A_TO_COMP_A_21_DP")
			(clearance 0.264414)
			(padstack
				(mode custom)
				(layer "In1.Cu"
					(shape circle)
					(size 0.664718 0.664718)
					(clearance 0.264414)
				)
				(layer "In2.Cu"
					(shape circle)
					(size 0.664718 0.664718)
					(clearance 0.264414)
				)
				(layer "In3.Cu"
					(shape circle)
					(size 0.664718 0.664718)
					(clearance 0.264414)
				)
				(layer "In4.Cu"
					(shape circle)
					(size 0.664718 0.664718)
					(clearance 0.264414)
				)
				(layer "In5.Cu"
					(shape circle)
					(size 0.664718 0.664718)
					(clearance 0.264414)
				)
				(layer "In6.Cu"
					(shape circle)
					(size 0.762 0.762)
					(clearance 0.1651)
				)
				(layer "In7.Cu"
					(shape circle)
					(size 0.762 0.762)
					(clearance 0.1651)
				)
				(layer "In8.Cu"
					(shape circle)
					(size 0.762 0.762)
					(clearance 0.1651)
				)
				(layer "In9.Cu"
					(shape circle)
					(size 0.762 0.762)
					(clearance 0.1651)
				)
				(layer "In10.Cu"
					(shape circle)
					(size 0.762 0.762)
					(clearance 0.1651)
				)
				(layer "B.Cu"
					(shape circle)
					(size 0.762 0.762)
					(thermal_gap 0.1651)
					(clearance 0.1651)
				)
			)
		)
		(pad "F15" thru_hole circle
			(at 32.399986 -8.599932)
			(size 0.664718 0.664718)
			(drill 0.359918)
			(layers "*.Cu" "*.Mask")
			(remove_unused_layers no)
			(net "PCIE_IOM_A_TO_COMP_A_22_DP")
			(clearance 0.264414)
			(padstack
				(mode custom)
				(layer "In1.Cu"
					(shape circle)
					(size 0.664718 0.664718)
					(clearance 0.264414)
				)
				(layer "In2.Cu"
					(shape circle)
					(size 0.664718 0.664718)
					(clearance 0.264414)
				)
				(layer "In3.Cu"
					(shape circle)
					(size 0.664718 0.664718)
					(clearance 0.264414)
				)
				(layer "In4.Cu"
					(shape circle)
					(size 0.664718 0.664718)
					(clearance 0.264414)
				)
				(layer "In5.Cu"
					(shape circle)
					(size 0.664718 0.664718)
					(clearance 0.264414)
				)
				(layer "In6.Cu"
					(shape circle)
					(size 0.762 0.762)
					(clearance 0.1651)
				)
				(layer "In7.Cu"
					(shape circle)
					(size 0.762 0.762)
					(clearance 0.1651)
				)
				(layer "In8.Cu"
					(shape circle)
					(size 0.762 0.762)
					(clearance 0.1651)
				)
				(layer "In9.Cu"
					(shape circle)
					(size 0.762 0.762)
					(clearance 0.1651)
				)
				(layer "In10.Cu"
					(shape circle)
					(size 0.762 0.762)
					(clearance 0.1651)
				)
				(layer "B.Cu"
					(shape circle)
					(size 0.762 0.762)
					(thermal_gap 0.1651)
					(clearance 0.1651)
				)
			)
		)
		(pad "F16" thru_hole circle
			(at 34.200084 -9.59993)
			(size 0.664718 0.664718)
			(drill 0.359918)
			(layers "*.Cu" "*.Mask")
			(remove_unused_layers no)
			(net "PCIE_IOM_A_TO_COMP_A_23_DP")
			(clearance 0.264414)
			(padstack
				(mode custom)
				(layer "In1.Cu"
					(shape circle)
					(size 0.664718 0.664718)
					(clearance 0.264414)
				)
				(layer "In2.Cu"
					(shape circle)
					(size 0.664718 0.664718)
					(clearance 0.264414)
				)
				(layer "In3.Cu"
					(shape circle)
					(size 0.664718 0.664718)
					(clearance 0.264414)
				)
				(layer "In4.Cu"
					(shape circle)
					(size 0.664718 0.664718)
					(clearance 0.264414)
				)
				(layer "In5.Cu"
					(shape circle)
					(size 0.664718 0.664718)
					(clearance 0.264414)
				)
				(layer "In6.Cu"
					(shape circle)
					(size 0.762 0.762)
					(clearance 0.1651)
				)
				(layer "In7.Cu"
					(shape circle)
					(size 0.762 0.762)
					(clearance 0.1651)
				)
				(layer "In8.Cu"
					(shape circle)
					(size 0.762 0.762)
					(clearance 0.1651)
				)
				(layer "In9.Cu"
					(shape circle)
					(size 0.762 0.762)
					(clearance 0.1651)
				)
				(layer "In10.Cu"
					(shape circle)
					(size 0.762 0.762)
					(clearance 0.1651)
				)
				(layer "B.Cu"
					(shape circle)
					(size 0.762 0.762)
					(thermal_gap 0.1651)
					(clearance 0.1651)
				)
			)
		)
		(pad "G1" thru_hole circle
			(at 0 -10.80008)
			(size 0.664718 0.664718)
			(drill 0.359918)
			(layers "*.Cu" "*.Mask")
			(remove_unused_layers no)
			(net "PCIE_COMP_A_TO_IOM_A_8_DN")
			(clearance 0.264414)
			(padstack
				(mode custom)
				(layer "In1.Cu"
					(shape circle)
					(size 0.664718 0.664718)
					(clearance 0.264414)
				)
				(layer "In2.Cu"
					(shape circle)
					(size 0.664718 0.664718)
					(clearance 0.264414)
				)
				(layer "In3.Cu"
					(shape circle)
					(size 0.664718 0.664718)
					(clearance 0.264414)
				)
				(layer "In4.Cu"
					(shape circle)
					(size 0.664718 0.664718)
					(clearance 0.264414)
				)
				(layer "In5.Cu"
					(shape circle)
					(size 0.664718 0.664718)
					(clearance 0.264414)
				)
				(layer "In6.Cu"
					(shape circle)
					(size 0.762 0.762)
					(clearance 0.1651)
				)
				(layer "In7.Cu"
					(shape circle)
					(size 0.762 0.762)
					(clearance 0.1651)
				)
				(layer "In8.Cu"
					(shape circle)
					(size 0.762 0.762)
					(clearance 0.1651)
				)
				(layer "In9.Cu"
					(shape circle)
					(size 0.762 0.762)
					(clearance 0.1651)
				)
				(layer "In10.Cu"
					(shape circle)
					(size 0.762 0.762)
					(clearance 0.1651)
				)
				(layer "B.Cu"
					(shape circle)
					(size 0.762 0.762)
					(thermal_gap 0.1651)
					(clearance 0.1651)
				)
			)
		)
		(pad "G2" thru_hole circle
			(at 1.800098 -11.800078)
			(size 0.664718 0.664718)
			(drill 0.359918)
			(layers "*.Cu" "*.Mask")
			(remove_unused_layers no)
			(net "PCIE_COMP_A_TO_IOM_A_9_DN")
			(clearance 0.264414)
			(padstack
				(mode custom)
				(layer "In1.Cu"
					(shape circle)
					(size 0.664718 0.664718)
					(clearance 0.264414)
				)
				(layer "In2.Cu"
					(shape circle)
					(size 0.664718 0.664718)
					(clearance 0.264414)
				)
				(layer "In3.Cu"
					(shape circle)
					(size 0.664718 0.664718)
					(clearance 0.264414)
				)
				(layer "In4.Cu"
					(shape circle)
					(size 0.664718 0.664718)
					(clearance 0.264414)
				)
				(layer "In5.Cu"
					(shape circle)
					(size 0.664718 0.664718)
					(clearance 0.264414)
				)
				(layer "In6.Cu"
					(shape circle)
					(size 0.762 0.762)
					(clearance 0.1651)
				)
				(layer "In7.Cu"
					(shape circle)
					(size 0.762 0.762)
					(clearance 0.1651)
				)
				(layer "In8.Cu"
					(shape circle)
					(size 0.762 0.762)
					(clearance 0.1651)
				)
				(layer "In9.Cu"
					(shape circle)
					(size 0.762 0.762)
					(clearance 0.1651)
				)
				(layer "In10.Cu"
					(shape circle)
					(size 0.762 0.762)
					(clearance 0.1651)
				)
				(layer "B.Cu"
					(shape circle)
					(size 0.762 0.762)
					(thermal_gap 0.1651)
					(clearance 0.1651)
				)
			)
		)
		(pad "G3" thru_hole circle
			(at 3.599942 -10.80008)
			(size 0.664718 0.664718)
			(drill 0.359918)
			(layers "*.Cu" "*.Mask")
			(remove_unused_layers no)
			(net "PCIE_COMP_A_TO_IOM_A_10_DN")
			(clearance 0.264414)
			(padstack
				(mode custom)
				(layer "In1.Cu"
					(shape circle)
					(size 0.664718 0.664718)
					(clearance 0.264414)
				)
				(layer "In2.Cu"
					(shape circle)
					(size 0.664718 0.664718)
					(clearance 0.264414)
				)
				(layer "In3.Cu"
					(shape circle)
					(size 0.664718 0.664718)
					(clearance 0.264414)
				)
				(layer "In4.Cu"
					(shape circle)
					(size 0.664718 0.664718)
					(clearance 0.264414)
				)
				(layer "In5.Cu"
					(shape circle)
					(size 0.664718 0.664718)
					(clearance 0.264414)
				)
				(layer "In6.Cu"
					(shape circle)
					(size 0.762 0.762)
					(clearance 0.1651)
				)
				(layer "In7.Cu"
					(shape circle)
					(size 0.762 0.762)
					(clearance 0.1651)
				)
				(layer "In8.Cu"
					(shape circle)
					(size 0.762 0.762)
					(clearance 0.1651)
				)
				(layer "In9.Cu"
					(shape circle)
					(size 0.762 0.762)
					(clearance 0.1651)
				)
				(layer "In10.Cu"
					(shape circle)
					(size 0.762 0.762)
					(clearance 0.1651)
				)
				(layer "B.Cu"
					(shape circle)
					(size 0.762 0.762)
					(thermal_gap 0.1651)
					(clearance 0.1651)
				)
			)
		)
		(pad "G4" thru_hole circle
			(at 5.40004 -11.800078)
			(size 0.664718 0.664718)
			(drill 0.359918)
			(layers "*.Cu" "*.Mask")
			(remove_unused_layers no)
			(net "PCIE_COMP_A_TO_IOM_A_11_DN")
			(clearance 0.264414)
			(padstack
				(mode custom)
				(layer "In1.Cu"
					(shape circle)
					(size 0.664718 0.664718)
					(clearance 0.264414)
				)
				(layer "In2.Cu"
					(shape circle)
					(size 0.664718 0.664718)
					(clearance 0.264414)
				)
				(layer "In3.Cu"
					(shape circle)
					(size 0.664718 0.664718)
					(clearance 0.264414)
				)
				(layer "In4.Cu"
					(shape circle)
					(size 0.664718 0.664718)
					(clearance 0.264414)
				)
				(layer "In5.Cu"
					(shape circle)
					(size 0.664718 0.664718)
					(clearance 0.264414)
				)
				(layer "In6.Cu"
					(shape circle)
					(size 0.762 0.762)
					(clearance 0.1651)
				)
				(layer "In7.Cu"
					(shape circle)
					(size 0.762 0.762)
					(clearance 0.1651)
				)
				(layer "In8.Cu"
					(shape circle)
					(size 0.762 0.762)
					(clearance 0.1651)
				)
				(layer "In9.Cu"
					(shape circle)
					(size 0.762 0.762)
					(clearance 0.1651)
				)
				(layer "In10.Cu"
					(shape circle)
					(size 0.762 0.762)
					(clearance 0.1651)
				)
				(layer "B.Cu"
					(shape circle)
					(size 0.762 0.762)
					(thermal_gap 0.1651)
					(clearance 0.1651)
				)
			)
		)
		(pad "G5" thru_hole circle
			(at 7.199884 -10.80008)
			(size 0.664718 0.664718)
			(drill 0.359918)
			(layers "*.Cu" "*.Mask")
			(remove_unused_layers no)
			(net "PCIE_COMP_A_TO_IOM_A_12_DN")
			(clearance 0.264414)
			(padstack
				(mode custom)
				(layer "In1.Cu"
					(shape circle)
					(size 0.664718 0.664718)
					(clearance 0.264414)
				)
				(layer "In2.Cu"
					(shape circle)
					(size 0.664718 0.664718)
					(clearance 0.264414)
				)
				(layer "In3.Cu"
					(shape circle)
					(size 0.664718 0.664718)
					(clearance 0.264414)
				)
				(layer "In4.Cu"
					(shape circle)
					(size 0.664718 0.664718)
					(clearance 0.264414)
				)
				(layer "In5.Cu"
					(shape circle)
					(size 0.664718 0.664718)
					(clearance 0.264414)
				)
				(layer "In6.Cu"
					(shape circle)
					(size 0.762 0.762)
					(clearance 0.1651)
				)
				(layer "In7.Cu"
					(shape circle)
					(size 0.762 0.762)
					(clearance 0.1651)
				)
				(layer "In8.Cu"
					(shape circle)
					(size 0.762 0.762)
					(clearance 0.1651)
				)
				(layer "In9.Cu"
					(shape circle)
					(size 0.762 0.762)
					(clearance 0.1651)
				)
				(layer "In10.Cu"
					(shape circle)
					(size 0.762 0.762)
					(clearance 0.1651)
				)
				(layer "B.Cu"
					(shape circle)
					(size 0.762 0.762)
					(thermal_gap 0.1651)
					(clearance 0.1651)
				)
			)
		)
		(pad "G6" thru_hole circle
			(at 8.999982 -11.800078)
			(size 0.664718 0.664718)
			(drill 0.359918)
			(layers "*.Cu" "*.Mask")
			(remove_unused_layers no)
			(net "PCIE_COMP_A_TO_IOM_A_13_DN")
			(clearance 0.264414)
			(padstack
				(mode custom)
				(layer "In1.Cu"
					(shape circle)
					(size 0.664718 0.664718)
					(clearance 0.264414)
				)
				(layer "In2.Cu"
					(shape circle)
					(size 0.664718 0.664718)
					(clearance 0.264414)
				)
				(layer "In3.Cu"
					(shape circle)
					(size 0.664718 0.664718)
					(clearance 0.264414)
				)
				(layer "In4.Cu"
					(shape circle)
					(size 0.664718 0.664718)
					(clearance 0.264414)
				)
				(layer "In5.Cu"
					(shape circle)
					(size 0.664718 0.664718)
					(clearance 0.264414)
				)
				(layer "In6.Cu"
					(shape circle)
					(size 0.762 0.762)
					(clearance 0.1651)
				)
				(layer "In7.Cu"
					(shape circle)
					(size 0.762 0.762)
					(clearance 0.1651)
				)
				(layer "In8.Cu"
					(shape circle)
					(size 0.762 0.762)
					(clearance 0.1651)
				)
				(layer "In9.Cu"
					(shape circle)
					(size 0.762 0.762)
					(clearance 0.1651)
				)
				(layer "In10.Cu"
					(shape circle)
					(size 0.762 0.762)
					(clearance 0.1651)
				)
				(layer "B.Cu"
					(shape circle)
					(size 0.762 0.762)
					(thermal_gap 0.1651)
					(clearance 0.1651)
				)
			)
		)
		(pad "G7" thru_hole circle
			(at 10.80008 -10.80008)
			(size 0.664718 0.664718)
			(drill 0.359918)
			(layers "*.Cu" "*.Mask")
			(remove_unused_layers no)
			(net "PCIE_COMP_A_TO_IOM_A_14_DN")
			(clearance 0.264414)
			(padstack
				(mode custom)
				(layer "In1.Cu"
					(shape circle)
					(size 0.664718 0.664718)
					(clearance 0.264414)
				)
				(layer "In2.Cu"
					(shape circle)
					(size 0.664718 0.664718)
					(clearance 0.264414)
				)
				(layer "In3.Cu"
					(shape circle)
					(size 0.664718 0.664718)
					(clearance 0.264414)
				)
				(layer "In4.Cu"
					(shape circle)
					(size 0.664718 0.664718)
					(clearance 0.264414)
				)
				(layer "In5.Cu"
					(shape circle)
					(size 0.664718 0.664718)
					(clearance 0.264414)
				)
				(layer "In6.Cu"
					(shape circle)
					(size 0.762 0.762)
					(clearance 0.1651)
				)
				(layer "In7.Cu"
					(shape circle)
					(size 0.762 0.762)
					(clearance 0.1651)
				)
				(layer "In8.Cu"
					(shape circle)
					(size 0.762 0.762)
					(clearance 0.1651)
				)
				(layer "In9.Cu"
					(shape circle)
					(size 0.762 0.762)
					(clearance 0.1651)
				)
				(layer "In10.Cu"
					(shape circle)
					(size 0.762 0.762)
					(clearance 0.1651)
				)
				(layer "B.Cu"
					(shape circle)
					(size 0.762 0.762)
					(thermal_gap 0.1651)
					(clearance 0.1651)
				)
			)
		)
		(pad "G8" thru_hole circle
			(at 12.599924 -11.800078)
			(size 0.664718 0.664718)
			(drill 0.359918)
			(layers "*.Cu" "*.Mask")
			(remove_unused_layers no)
			(net "PCIE_COMP_A_TO_IOM_A_15_DN")
			(clearance 0.264414)
			(padstack
				(mode custom)
				(layer "In1.Cu"
					(shape circle)
					(size 0.664718 0.664718)
					(clearance 0.264414)
				)
				(layer "In2.Cu"
					(shape circle)
					(size 0.664718 0.664718)
					(clearance 0.264414)
				)
				(layer "In3.Cu"
					(shape circle)
					(size 0.664718 0.664718)
					(clearance 0.264414)
				)
				(layer "In4.Cu"
					(shape circle)
					(size 0.664718 0.664718)
					(clearance 0.264414)
				)
				(layer "In5.Cu"
					(shape circle)
					(size 0.664718 0.664718)
					(clearance 0.264414)
				)
				(layer "In6.Cu"
					(shape circle)
					(size 0.762 0.762)
					(clearance 0.1651)
				)
				(layer "In7.Cu"
					(shape circle)
					(size 0.762 0.762)
					(clearance 0.1651)
				)
				(layer "In8.Cu"
					(shape circle)
					(size 0.762 0.762)
					(clearance 0.1651)
				)
				(layer "In9.Cu"
					(shape circle)
					(size 0.762 0.762)
					(clearance 0.1651)
				)
				(layer "In10.Cu"
					(shape circle)
					(size 0.762 0.762)
					(clearance 0.1651)
				)
				(layer "B.Cu"
					(shape circle)
					(size 0.762 0.762)
					(thermal_gap 0.1651)
					(clearance 0.1651)
				)
			)
		)
		(pad "G9" thru_hole circle
			(at 21.599906 -10.80008)
			(size 0.664718 0.664718)
			(drill 0.359918)
			(layers "*.Cu" "*.Mask")
			(remove_unused_layers no)
			(net "PCIE_COMP_A_TO_IOM_A_16_DN")
			(clearance 0.264414)
			(padstack
				(mode custom)
				(layer "In1.Cu"
					(shape circle)
					(size 0.664718 0.664718)
					(clearance 0.264414)
				)
				(layer "In2.Cu"
					(shape circle)
					(size 0.664718 0.664718)
					(clearance 0.264414)
				)
				(layer "In3.Cu"
					(shape circle)
					(size 0.664718 0.664718)
					(clearance 0.264414)
				)
				(layer "In4.Cu"
					(shape circle)
					(size 0.664718 0.664718)
					(clearance 0.264414)
				)
				(layer "In5.Cu"
					(shape circle)
					(size 0.664718 0.664718)
					(clearance 0.264414)
				)
				(layer "In6.Cu"
					(shape circle)
					(size 0.762 0.762)
					(clearance 0.1651)
				)
				(layer "In7.Cu"
					(shape circle)
					(size 0.762 0.762)
					(clearance 0.1651)
				)
				(layer "In8.Cu"
					(shape circle)
					(size 0.762 0.762)
					(clearance 0.1651)
				)
				(layer "In9.Cu"
					(shape circle)
					(size 0.762 0.762)
					(clearance 0.1651)
				)
				(layer "In10.Cu"
					(shape circle)
					(size 0.762 0.762)
					(clearance 0.1651)
				)
				(layer "B.Cu"
					(shape circle)
					(size 0.762 0.762)
					(thermal_gap 0.1651)
					(clearance 0.1651)
				)
			)
		)
		(pad "G10" thru_hole circle
			(at 23.400004 -11.800078)
			(size 0.664718 0.664718)
			(drill 0.359918)
			(layers "*.Cu" "*.Mask")
			(remove_unused_layers no)
			(net "PCIE_COMP_A_TO_IOM_A_17_DN")
			(clearance 0.264414)
			(padstack
				(mode custom)
				(layer "In1.Cu"
					(shape circle)
					(size 0.664718 0.664718)
					(clearance 0.264414)
				)
				(layer "In2.Cu"
					(shape circle)
					(size 0.664718 0.664718)
					(clearance 0.264414)
				)
				(layer "In3.Cu"
					(shape circle)
					(size 0.664718 0.664718)
					(clearance 0.264414)
				)
				(layer "In4.Cu"
					(shape circle)
					(size 0.664718 0.664718)
					(clearance 0.264414)
				)
				(layer "In5.Cu"
					(shape circle)
					(size 0.664718 0.664718)
					(clearance 0.264414)
				)
				(layer "In6.Cu"
					(shape circle)
					(size 0.762 0.762)
					(clearance 0.1651)
				)
				(layer "In7.Cu"
					(shape circle)
					(size 0.762 0.762)
					(clearance 0.1651)
				)
				(layer "In8.Cu"
					(shape circle)
					(size 0.762 0.762)
					(clearance 0.1651)
				)
				(layer "In9.Cu"
					(shape circle)
					(size 0.762 0.762)
					(clearance 0.1651)
				)
				(layer "In10.Cu"
					(shape circle)
					(size 0.762 0.762)
					(clearance 0.1651)
				)
				(layer "B.Cu"
					(shape circle)
					(size 0.762 0.762)
					(thermal_gap 0.1651)
					(clearance 0.1651)
				)
			)
		)
		(pad "G11" thru_hole circle
			(at 25.200102 -10.80008)
			(size 0.664718 0.664718)
			(drill 0.359918)
			(layers "*.Cu" "*.Mask")
			(remove_unused_layers no)
			(net "PCIE_COMP_A_TO_IOM_A_18_DN")
			(clearance 0.264414)
			(padstack
				(mode custom)
				(layer "In1.Cu"
					(shape circle)
					(size 0.664718 0.664718)
					(clearance 0.264414)
				)
				(layer "In2.Cu"
					(shape circle)
					(size 0.664718 0.664718)
					(clearance 0.264414)
				)
				(layer "In3.Cu"
					(shape circle)
					(size 0.664718 0.664718)
					(clearance 0.264414)
				)
				(layer "In4.Cu"
					(shape circle)
					(size 0.664718 0.664718)
					(clearance 0.264414)
				)
				(layer "In5.Cu"
					(shape circle)
					(size 0.664718 0.664718)
					(clearance 0.264414)
				)
				(layer "In6.Cu"
					(shape circle)
					(size 0.762 0.762)
					(clearance 0.1651)
				)
				(layer "In7.Cu"
					(shape circle)
					(size 0.762 0.762)
					(clearance 0.1651)
				)
				(layer "In8.Cu"
					(shape circle)
					(size 0.762 0.762)
					(clearance 0.1651)
				)
				(layer "In9.Cu"
					(shape circle)
					(size 0.762 0.762)
					(clearance 0.1651)
				)
				(layer "In10.Cu"
					(shape circle)
					(size 0.762 0.762)
					(clearance 0.1651)
				)
				(layer "B.Cu"
					(shape circle)
					(size 0.762 0.762)
					(thermal_gap 0.1651)
					(clearance 0.1651)
				)
			)
		)
	)
)
